(kicad_pcb
	(version 20260206)
	(generator "pcbnew")
	(generator_version "10.0")
	(general
		(thickness 1.6)
		(legacy_teardrops no)
	)
	(paper "A4")
	(title_block
		(title "04192023_DAF0TMB3IC0_F0TG_MB_C_brd_V02_OCP.brd")
		(comment 1 "Grand Teton / footprints 3154-3161 of 8354")
	)
	(layers
		(0 "F.Cu" signal "TOP")
		(4 "In1.Cu" signal "GND")
		(6 "In2.Cu" signal "IN1")
		(8 "In3.Cu" signal "GND1")
		(10 "In4.Cu" signal "IN2")
		(12 "In5.Cu" signal "GND2")
		(14 "In6.Cu" signal "IN3")
		(16 "In7.Cu" signal "GND3")
		(18 "In8.Cu" signal "VCC")
		(20 "In9.Cu" signal "VCC1")
		(22 "In10.Cu" signal "GND4")
		(24 "In11.Cu" signal "IN4")
		(26 "In12.Cu" signal "GND5")
		(28 "In13.Cu" signal "IN5")
		(30 "In14.Cu" signal "GND6")
		(32 "In15.Cu" signal "IN6")
		(34 "In16.Cu" signal "GND7")
		(2 "B.Cu" signal "BOTTOM")
		(9 "F.Adhes" user "F.Adhesive")
		(11 "B.Adhes" user "B.Adhesive")
		(13 "F.Paste" user "Package Geometry/Pastemask Top")
		(15 "B.Paste" user "Package Geometry/Pastemask Bottom")
		(5 "F.SilkS" user "Ref Des/Silkscreen Top")
		(7 "B.SilkS" user "Ref Des/Silkscreen Bottom")
		(1 "F.Mask" user "Board Geometry/Soldermask Top")
		(3 "B.Mask" user "Board Geometry/Soldermask Bottom")
		(17 "Dwgs.User" user "User.Drawings")
		(19 "Cmts.User" user "User.Comments")
		(21 "Eco1.User" user "User.Eco1")
		(23 "Eco2.User" user "User.Eco2")
		(25 "Edge.Cuts" user "Board Geometry/Outline")
		(27 "Margin" user)
		(31 "F.CrtYd" user "Package Geometry/Place Bound Top")
		(29 "B.CrtYd" user "Package Geometry/Place Bound Bottom")
		(35 "F.Fab" user "Ref Des/Assembly Top")
		(33 "B.Fab" user "Ref Des/Assembly Bottom")
	)
	(footprint ""
		(layer "F.Cu")
		(at 447.557652 -17.433798 180)
		(property "Reference" "PR3788"
			(at 0 0 180)
			(layer "F.SilkS")
			(hide yes)
			(effects
				(font
					(size 1.27 1.27)
				)
			)
		)
		(property "Value" ""
			(at 0 0 180)
			(layer "F.Fab")
			(effects
				(font
					(size 1.27 1.27)
				)
			)
		)
		(duplicate_pad_numbers_are_jumpers no)
		(fp_line
			(start 0.7874 0.4064)
			(end -0.7874 0.4064)
			(stroke
				(width 0.1524)
				(type default)
			)
			(layer "F.SilkS")
		)
		(fp_line
			(start 0.7874 -0.4064)
			(end 0.7874 0.4064)
			(stroke
				(width 0.1524)
				(type default)
			)
			(layer "F.SilkS")
		)
		(fp_line
			(start -0.7874 0.4064)
			(end -0.7874 -0.4064)
			(stroke
				(width 0.1524)
				(type default)
			)
			(layer "F.SilkS")
		)
		(fp_line
			(start -0.7874 -0.4064)
			(end 0.7874 -0.4064)
			(stroke
				(width 0.1524)
				(type default)
			)
			(layer "F.SilkS")
		)
		(fp_line
			(start 0.67945 0.3048)
			(end 0.120396 0.3048)
			(stroke
				(width 0.1)
				(type default)
			)
			(layer "F.Fab")
		)
		(fp_line
			(start 0.67945 -0.3048)
			(end 0.67945 0.3048)
			(stroke
				(width 0.1)
				(type default)
			)
			(layer "F.Fab")
		)
		(fp_line
			(start 0.12065 -0.2794)
			(end 0.12065 -0.3048)
			(stroke
				(width 0.1)
				(type default)
			)
			(layer "F.Fab")
		)
		(fp_line
			(start 0.12065 -0.3048)
			(end 0.67945 -0.3048)
			(stroke
				(width 0.1)
				(type default)
			)
			(layer "F.Fab")
		)
		(fp_line
			(start 0.120396 0.3048)
			(end 0.120396 0.2794)
			(stroke
				(width 0.1)
				(type default)
			)
			(layer "F.Fab")
		)
		(fp_line
			(start 0.120396 0.2794)
			(end -0.12065 0.2794)
			(stroke
				(width 0.1)
				(type default)
			)
			(layer "F.Fab")
		)
		(fp_line
			(start -0.12065 0.3048)
			(end -0.67945 0.3048)
			(stroke
				(width 0.1)
				(type default)
			)
			(layer "F.Fab")
		)
		(fp_line
			(start -0.12065 0.2794)
			(end -0.12065 0.3048)
			(stroke
				(width 0.1)
				(type default)
			)
			(layer "F.Fab")
		)
		(fp_line
			(start -0.12065 -0.2794)
			(end 0.12065 -0.2794)
			(stroke
				(width 0.1)
				(type default)
			)
			(layer "F.Fab")
		)
		(fp_line
			(start -0.12065 -0.305054)
			(end -0.12065 -0.2794)
			(stroke
				(width 0.1)
				(type default)
			)
			(layer "F.Fab")
		)
		(fp_line
			(start -0.67945 0.3048)
			(end -0.67945 -0.305054)
			(stroke
				(width 0.1)
				(type default)
			)
			(layer "F.Fab")
		)
		(fp_line
			(start -0.67945 -0.305054)
			(end -0.12065 -0.305054)
			(stroke
				(width 0.1)
				(type default)
			)
			(layer "F.Fab")
		)
		(pad "1" smd circle
			(at -0.40005 0 180)
			(size 0 0)
			(layers "F.Cu" "F.Mask" "F.Paste")
			(net "P12V_OCP_OV_1")
		)
		(pad "2" smd circle
			(at 0.40005 0 180)
			(size 0 0)
			(layers "F.Cu" "F.Mask" "F.Paste")
			(net "GND")
		)
	)
	(footprint ""
		(layer "F.Cu")
		(at 414.792922 -173.084998 180)
		(property "Reference" "PL66"
			(at 0.04445 5.886704 90)
			(unlocked yes)
			(layer "F.SilkS")
			(effects
				(font
					(size 0.7874 0.5842)
					(thickness 0.1524)
				)
				(justify left)
			)
		)
		(property "Value" ""
			(at 0 0 180)
			(layer "F.Fab")
			(effects
				(font
					(size 1.27 1.27)
				)
			)
		)
		(duplicate_pad_numbers_are_jumpers no)
		(fp_line
			(start 3.750056 5.500116)
			(end 3.750056 -5.500116)
			(stroke
				(width 0.1524)
				(type default)
			)
			(layer "F.SilkS")
		)
		(fp_line
			(start 3.750056 -5.500116)
			(end 2.393442 -5.500116)
			(stroke
				(width 0.1524)
				(type default)
			)
			(layer "F.SilkS")
		)
		(fp_line
			(start 2.393442 5.500116)
			(end 3.750056 5.500116)
			(stroke
				(width 0.1524)
				(type default)
			)
			(layer "F.SilkS")
		)
		(fp_line
			(start -2.393442 5.500116)
			(end -3.750056 5.500116)
			(stroke
				(width 0.1524)
				(type default)
			)
			(layer "F.SilkS")
		)
		(fp_line
			(start -3.750056 5.500116)
			(end -3.750056 -5.500116)
			(stroke
				(width 0.1524)
				(type default)
			)
			(layer "F.SilkS")
		)
		(fp_line
			(start -3.750056 -5.500116)
			(end -2.393442 -5.500116)
			(stroke
				(width 0.1524)
				(type default)
			)
			(layer "F.SilkS")
		)
		(fp_poly
			(pts
				(xy -3.9116 -4.249928) (xy -4.434078 -3.988562) (xy -4.434078 -4.511294)
			)
			(stroke
				(width 0)
				(type default)
			)
			(fill yes)
			(layer "F.SilkS")
		)
		(fp_line
			(start 3.750056 5.500116)
			(end 3.750056 -5.500116)
			(stroke
				(width 0.1)
				(type default)
			)
			(layer "F.Fab")
		)
		(fp_line
			(start 3.750056 -5.500116)
			(end -3.750056 -5.500116)
			(stroke
				(width 0.1)
				(type default)
			)
			(layer "F.Fab")
		)
		(fp_line
			(start -3.750056 5.500116)
			(end 3.750056 5.500116)
			(stroke
				(width 0.1)
				(type default)
			)
			(layer "F.Fab")
		)
		(fp_line
			(start -3.750056 -5.500116)
			(end -3.750056 5.500116)
			(stroke
				(width 0.1)
				(type default)
			)
			(layer "F.Fab")
		)
		(fp_poly
			(pts
				(xy -4.9276 -4.757928) (xy -4.9276 -3.741928) (xy -3.9116 -4.249928)
			)
			(stroke
				(width 0)
				(type default)
			)
			(fill yes)
			(layer "F.Fab")
		)
		(pad "1" smd rect
			(at 0 -4.249928 90)
			(size 2.413 4.5212)
			(layers "F.Cu" "F.Mask" "F.Paste")
			(net "SW_PVDDCR_SOC_P0_SW3")
		)
		(pad "2" smd rect
			(at 0 -1.175004 90)
			(size 1.3716 4.5212)
			(layers "F.Cu" "F.Mask" "F.Paste")
			(net "IND_SOC_P0_CPL0")
		)
		(pad "3" smd rect
			(at 0 1.175004 90)
			(size 1.3716 4.5212)
			(layers "F.Cu" "F.Mask" "F.Paste")
			(net "IND_SOC_P0_CPL3")
		)
		(pad "4" smd rect
			(at 0 4.249928 90)
			(size 2.413 4.5212)
			(layers "F.Cu" "F.Mask" "F.Paste")
			(net "PVDDCR_SOC_P0")
		)
	)
	(footprint ""
		(layer "F.Cu")
		(at 113.339372 -403.724618 -90)
		(property "Reference" "R1213"
			(at 0 0 270)
			(layer "F.SilkS")
			(hide yes)
			(effects
				(font
					(size 1.27 1.27)
				)
			)
		)
		(property "Value" ""
			(at 0 0 270)
			(layer "F.Fab")
			(effects
				(font
					(size 1.27 1.27)
				)
			)
		)
		(duplicate_pad_numbers_are_jumpers no)
		(fp_line
			(start -0.32512 0.175006)
			(end -0.32512 -0.175006)
			(stroke
				(width 0.1)
				(type default)
			)
			(layer "F.Fab")
		)
		(fp_line
			(start 0.32512 0.175006)
			(end -0.32512 0.175006)
			(stroke
				(width 0.1)
				(type default)
			)
			(layer "F.Fab")
		)
		(fp_line
			(start -0.32512 -0.175006)
			(end 0.32512 -0.175006)
			(stroke
				(width 0.1)
				(type default)
			)
			(layer "F.Fab")
		)
		(fp_line
			(start 0.32512 -0.175006)
			(end 0.32512 0.175006)
			(stroke
				(width 0.1)
				(type default)
			)
			(layer "F.Fab")
		)
		(pad "1" smd rect
			(at -0.2667 0 270)
			(size 0.3048 0.381)
			(layers "F.Cu" "F.Mask" "F.Paste")
			(net "GND")
		)
		(pad "2" smd rect
			(at 0.2667 0 90)
			(size 0.3048 0.381)
			(layers "F.Cu" "F.Mask" "F.Paste")
			(net "RT_ROM_MUX2_OE_N")
		)
	)
	(footprint ""
		(layer "F.Cu")
		(at 176.154334 -417.406328)
		(property "Reference" "Q9001"
			(at -2.792222 -1.82626 0)
			(unlocked yes)
			(layer "F.SilkS")
			(effects
				(font
					(size 0.7874 0.5842)
					(thickness 0.1524)
				)
				(justify left)
			)
		)
		(property "Value" ""
			(at 0 0 0)
			(layer "F.Fab")
			(effects
				(font
					(size 1.27 1.27)
				)
			)
		)
		(duplicate_pad_numbers_are_jumpers no)
		(fp_line
			(start -1.332738 -1.100074)
			(end -0.4826 -1.100074)
			(stroke
				(width 0.1524)
				(type default)
			)
			(layer "F.SilkS")
		)
		(fp_line
			(start -1.332738 1.100074)
			(end -1.332738 -1.100074)
			(stroke
				(width 0.1524)
				(type default)
			)
			(layer "F.SilkS")
		)
		(fp_line
			(start -0.4826 -1.100074)
			(end 0 -0.541274)
			(stroke
				(width 0.1524)
				(type default)
			)
			(layer "F.SilkS")
		)
		(fp_line
			(start 0 -0.541274)
			(end 0.4826 -1.100074)
			(stroke
				(width 0.1524)
				(type default)
			)
			(layer "F.SilkS")
		)
		(fp_line
			(start 0.4826 -1.100074)
			(end 1.332738 -1.100074)
			(stroke
				(width 0.1524)
				(type default)
			)
			(layer "F.SilkS")
		)
		(fp_line
			(start 1.332738 -1.100074)
			(end 1.332738 1.100074)
			(stroke
				(width 0.1524)
				(type default)
			)
			(layer "F.SilkS")
		)
		(fp_line
			(start 1.332738 1.100074)
			(end -1.332738 1.100074)
			(stroke
				(width 0.1524)
				(type default)
			)
			(layer "F.SilkS")
		)
		(fp_poly
			(pts
				(xy -2.2352 -0.298958) (xy -2.2352 -1.001014) (xy -1.533144 -0.649986)
			)
			(stroke
				(width 0)
				(type default)
			)
			(fill yes)
			(layer "F.SilkS")
		)
		(fp_line
			(start -0.674878 -1.100074)
			(end 0.674878 -1.100074)
			(stroke
				(width 0.1)
				(type default)
			)
			(layer "F.Fab")
		)
		(fp_line
			(start -0.674878 1.100074)
			(end -0.674878 -1.100074)
			(stroke
				(width 0.1)
				(type default)
			)
			(layer "F.Fab")
		)
		(fp_line
			(start 0.674878 -1.100074)
			(end 0.674878 1.100074)
			(stroke
				(width 0.1)
				(type default)
			)
			(layer "F.Fab")
		)
		(fp_line
			(start 0.674878 1.100074)
			(end -0.674878 1.100074)
			(stroke
				(width 0.1)
				(type default)
			)
			(layer "F.Fab")
		)
		(fp_poly
			(pts
				(xy -2.2352 -0.298958) (xy -2.2352 -1.001014) (xy -1.533144 -0.649986)
			)
			(stroke
				(width 0)
				(type default)
			)
			(fill yes)
			(layer "F.Fab")
		)
		(pad "1" smd rect
			(at -0.94996 -0.649986 90)
			(size 0.4318 0.508)
			(layers "F.Cu" "F.Mask" "F.Paste")
			(net "GND")
		)
		(pad "2" smd rect
			(at -0.94996 0 90)
			(size 0.4318 0.508)
			(layers "F.Cu" "F.Mask" "F.Paste")
			(net "PRSNT_CABLE_SWB_B2_N")
		)
		(pad "3" smd rect
			(at -0.94996 0.649986 90)
			(size 0.4318 0.508)
			(layers "F.Cu" "F.Mask" "F.Paste")
			(net "PRSNT_CABLE_SWB_B2_ISO_N")
		)
		(pad "4" smd rect
			(at 0.94996 0.649986 90)
			(size 0.4318 0.508)
			(layers "F.Cu" "F.Mask" "F.Paste")
			(net "GND")
		)
		(pad "5" smd rect
			(at 0.94996 0 90)
			(size 0.4318 0.508)
			(layers "F.Cu" "F.Mask" "F.Paste")
			(net "PRSNT_CABLE_SWB_B2")
		)
		(pad "6" smd rect
			(at 0.94996 -0.649986 90)
			(size 0.4318 0.508)
			(layers "F.Cu" "F.Mask" "F.Paste")
			(net "PRSNT_CABLE_SWB_B2")
		)
	)
	(footprint ""
		(layer "F.Cu")
		(at 82.989674 -165.962076 180)
		(property "Reference" "PC272"
			(at 2.327148 -2.902204 0)
			(unlocked yes)
			(layer "F.SilkS")
			(effects
				(font
					(size 0.7874 0.5842)
					(thickness 0.1524)
				)
				(justify left)
			)
		)
		(property "Value" ""
			(at 0 0 180)
			(layer "F.Fab")
			(effects
				(font
					(size 1.27 1.27)
				)
			)
		)
		(duplicate_pad_numbers_are_jumpers no)
		(fp_line
			(start -3.400044 1.249934)
			(end 3.400044 1.249934)
			(stroke
				(width 0.1524)
				(type default)
			)
			(layer "F.SilkS")
		)
		(fp_circle
			(center 0 1.249934)
			(end -3.400044 1.249934)
			(stroke
				(width 0.1524)
				(type default)
			)
			(fill no)
			(layer "F.SilkS")
		)
		(fp_poly
			(pts
				(arc
					(start 3.400044 1.249934)
					(mid 0 4.649978)
					(end -3.400044 1.249934)
				)
			)
			(stroke
				(width 0)
				(type default)
			)
			(fill yes)
			(layer "F.SilkS")
		)
		(fp_circle
			(center 0 1.249934)
			(end -3.400044 1.249934)
			(stroke
				(width 0.1)
				(type default)
			)
			(fill no)
			(layer "F.Fab")
		)
		(pad "1" thru_hole rect
			(at 0 0 180)
			(size 1.524 1.524)
			(drill 1.016)
			(layers "*.Cu" "*.Mask")
			(remove_unused_layers no)
			(net "SW_P12V_AUX_PVDDCR_CPU0_P1_FLT")
			(clearance 0)
			(padstack
				(mode front_inner_back)
				(layer "Inner"
					(shape circle)
					(size 1.524 1.524)
					(clearance 0)
				)
				(layer "B.Cu"
					(shape rect)
					(size 1.524 1.524)
					(clearance 0)
				)
			)
		)
		(pad "2" thru_hole circle
			(at 0 2.500122 180)
			(size 1.524 1.524)
			(drill 1.016)
			(layers "*.Cu" "*.Mask")
			(remove_unused_layers no)
			(net "GND")
			(clearance 0)
		)
	)
	(footprint ""
		(layer "F.Cu")
		(at 398.595088 -390.77646 180)
		(property "Reference" "C869"
			(at 0 0 180)
			(layer "F.SilkS")
			(hide yes)
			(effects
				(font
					(size 1.27 1.27)
				)
			)
		)
		(property "Value" ""
			(at 0 0 180)
			(layer "F.Fab")
			(effects
				(font
					(size 1.27 1.27)
				)
			)
		)
		(duplicate_pad_numbers_are_jumpers no)
		(fp_line
			(start 0.299974 0.150114)
			(end -0.299974 0.150114)
			(stroke
				(width 0.1)
				(type default)
			)
			(layer "F.Fab")
		)
		(fp_line
			(start 0.299974 -0.150114)
			(end 0.299974 0.150114)
			(stroke
				(width 0.1)
				(type default)
			)
			(layer "F.Fab")
		)
		(fp_line
			(start -0.299974 0.150114)
			(end -0.299974 -0.150114)
			(stroke
				(width 0.1)
				(type default)
			)
			(layer "F.Fab")
		)
		(fp_line
			(start -0.299974 -0.150114)
			(end 0.299974 -0.150114)
			(stroke
				(width 0.1)
				(type default)
			)
			(layer "F.Fab")
		)
		(pad "1" smd rect
			(at -0.2667 0 180)
			(size 0.3048 0.381)
			(layers "F.Cu" "F.Mask" "F.Paste")
			(net "P5E_CPU0_P2_TX_C_DP<0>")
		)
		(pad "2" smd rect
			(at 0.2667 0 180)
			(size 0.3048 0.381)
			(layers "F.Cu" "F.Mask" "F.Paste")
			(net "P5E_CPU0_P2_TX_DP<0>")
		)
	)
	(footprint ""
		(layer "F.Cu")
		(at 419.03904 -381.41783 -90)
		(property "Reference" "C847"
			(at 0 0 270)
			(layer "F.SilkS")
			(hide yes)
			(effects
				(font
					(size 1.27 1.27)
				)
			)
		)
		(property "Value" ""
			(at 0 0 270)
			(layer "F.Fab")
			(effects
				(font
					(size 1.27 1.27)
				)
			)
		)
		(duplicate_pad_numbers_are_jumpers no)
		(fp_line
			(start -0.299974 0.150114)
			(end -0.299974 -0.150114)
			(stroke
				(width 0.1)
				(type default)
			)
			(layer "F.Fab")
		)
		(fp_line
			(start 0.299974 0.150114)
			(end -0.299974 0.150114)
			(stroke
				(width 0.1)
				(type default)
			)
			(layer "F.Fab")
		)
		(fp_line
			(start -0.299974 -0.150114)
			(end 0.299974 -0.150114)
			(stroke
				(width 0.1)
				(type default)
			)
			(layer "F.Fab")
		)
		(fp_line
			(start 0.299974 -0.150114)
			(end 0.299974 0.150114)
			(stroke
				(width 0.1)
				(type default)
			)
			(layer "F.Fab")
		)
		(pad "1" smd rect
			(at -0.2667 0 270)
			(size 0.3048 0.381)
			(layers "F.Cu" "F.Mask" "F.Paste")
			(net "P5E_CPU0_P2_TX_C_DP<11>")
		)
		(pad "2" smd rect
			(at 0.2667 0 270)
			(size 0.3048 0.381)
			(layers "F.Cu" "F.Mask" "F.Paste")
			(net "P5E_CPU0_P2_TX_DP<11>")
		)
	)
	(footprint ""
		(layer "F.Cu")
		(at 212.993732 -112.662208 180)
		(property "Reference" "R132"
			(at 0 0 180)
			(layer "F.SilkS")
			(hide yes)
			(effects
				(font
					(size 1.27 1.27)
				)
			)
		)
		(property "Value" ""
			(at 0 0 180)
			(layer "F.Fab")
			(effects
				(font
					(size 1.27 1.27)
				)
			)
		)
		(duplicate_pad_numbers_are_jumpers no)
		(fp_line
			(start 0.7874 0.4064)
			(end -0.7874 0.4064)
			(stroke
				(width 0.1524)
				(type default)
			)
			(layer "F.SilkS")
		)
		(fp_line
			(start 0.7874 -0.4064)
			(end 0.7874 0.4064)
			(stroke
				(width 0.1524)
				(type default)
			)
			(layer "F.SilkS")
		)
		(fp_line
			(start -0.7874 0.4064)
			(end -0.7874 -0.4064)
			(stroke
				(width 0.1524)
				(type default)
			)
			(layer "F.SilkS")
		)
		(fp_line
			(start -0.7874 -0.4064)
			(end 0.7874 -0.4064)
			(stroke
				(width 0.1524)
				(type default)
			)
			(layer "F.SilkS")
		)
		(fp_line
			(start 0.67945 0.3048)
			(end 0.120396 0.3048)
			(stroke
				(width 0.1)
				(type default)
			)
			(layer "F.Fab")
		)
		(fp_line
			(start 0.67945 -0.3048)
			(end 0.67945 0.3048)
			(stroke
				(width 0.1)
				(type default)
			)
			(layer "F.Fab")
		)
		(fp_line
			(start 0.12065 -0.2794)
			(end 0.12065 -0.3048)
			(stroke
				(width 0.1)
				(type default)
			)
			(layer "F.Fab")
		)
		(fp_line
			(start 0.12065 -0.3048)
			(end 0.67945 -0.3048)
			(stroke
				(width 0.1)
				(type default)
			)
			(layer "F.Fab")
		)
		(fp_line
			(start 0.120396 0.3048)
			(end 0.120396 0.2794)
			(stroke
				(width 0.1)
				(type default)
			)
			(layer "F.Fab")
		)
		(fp_line
			(start 0.120396 0.2794)
			(end -0.12065 0.2794)
			(stroke
				(width 0.1)
				(type default)
			)
			(layer "F.Fab")
		)
		(fp_line
			(start -0.12065 0.3048)
			(end -0.67945 0.3048)
			(stroke
				(width 0.1)
				(type default)
			)
			(layer "F.Fab")
		)
		(fp_line
			(start -0.12065 0.2794)
			(end -0.12065 0.3048)
			(stroke
				(width 0.1)
				(type default)
			)
			(layer "F.Fab")
		)
		(fp_line
			(start -0.12065 -0.2794)
			(end 0.12065 -0.2794)
			(stroke
				(width 0.1)
				(type default)
			)
			(layer "F.Fab")
		)
		(fp_line
			(start -0.12065 -0.305054)
			(end -0.12065 -0.2794)
			(stroke
				(width 0.1)
				(type default)
			)
			(layer "F.Fab")
		)
		(fp_line
			(start -0.67945 0.3048)
			(end -0.67945 -0.305054)
			(stroke
				(width 0.1)
				(type default)
			)
			(layer "F.Fab")
		)
		(fp_line
			(start -0.67945 -0.305054)
			(end -0.12065 -0.305054)
			(stroke
				(width 0.1)
				(type default)
			)
			(layer "F.Fab")
		)
		(pad "1" smd circle
			(at -0.40005 0 180)
			(size 0 0)
			(layers "F.Cu" "F.Mask" "F.Paste")
			(net "FM_APML_MUX2_OE_N")
		)
		(pad "2" smd circle
			(at 0.40005 0 180)
			(size 0 0)
			(layers "F.Cu" "F.Mask" "F.Paste")
			(net "FM_APML_MUX2_OE_R_N")
		)
	)
)
